(kicad_pcb
	(version 20260206)
	(generator "pcbnew")
	(generator_version "10.0")
	(general
		(thickness 1.6)
		(legacy_teardrops no)
	)
	(paper "A4")
	(title_block
		(title "netronome-mezz — pcbd0082-001_rev01_jul9_a.brd")
		(comment 1 "Open CloudServer (Microsoft) / footprints 451-460 of 714")
	)
	(layers
		(0 "F.Cu" signal "TOP")
		(4 "In1.Cu" signal "02_GND")
		(6 "In2.Cu" signal "03_SIG")
		(8 "In3.Cu" signal "04_SIG")
		(10 "In4.Cu" signal "05_GND")
		(12 "In5.Cu" signal "06_PWR1")
		(14 "In6.Cu" signal "07_SIG")
		(16 "In7.Cu" signal "08_SIG")
		(18 "In8.Cu" signal "09_GND")
		(2 "B.Cu" signal "BOTTOM")
		(9 "F.Adhes" user "F.Adhesive")
		(11 "B.Adhes" user "B.Adhesive")
		(13 "F.Paste" user "Package Geometry/Pastemask Top")
		(15 "B.Paste" user "Package Geometry/Pastemask Bottom")
		(5 "F.SilkS" user "Ref Des/Silkscreen Top")
		(7 "B.SilkS" user "Ref Des/Silkscreen Bottom")
		(1 "F.Mask" user "Board Geometry/Soldermask Top")
		(3 "B.Mask" user "Board Geometry/Soldermask Bottom")
		(17 "Dwgs.User" user "User.Drawings")
		(19 "Cmts.User" user "User.Comments")
		(21 "Eco1.User" user "User.Eco1")
		(23 "Eco2.User" user "User.Eco2")
		(25 "Edge.Cuts" user "Board Geometry/Outline")
		(27 "Margin" user)
		(31 "F.CrtYd" user "Package Geometry/Place Bound Top")
		(29 "B.CrtYd" user "Package Geometry/Place Bound Bottom")
		(35 "F.Fab" user "Ref Des/Assembly Top")
		(33 "B.Fab" user "Ref Des/Assembly Bottom")
		(45 "User.4" user "COMPVAL_TYPE_BOTTOM")
	)
	(footprint ""
		(layer "B.Cu")
		(at 54.737 33.782)
		(property "Reference" "C14"
			(at 0.98933 0.254 270)
			(unlocked yes)
			(layer "B.SilkS")
			(effects
				(font
					(size 0.7874 0.5842)
					(thickness 0.127)
				)
				(justify left mirror)
			)
		)
		(property "Value" "22UF"
			(at 0.148158 1.7526 270)
			(unlocked yes)
			(layer "B.Fab")
			(hide yes)
			(effects
				(font
					(size 1.27 0.9652)
					(thickness 0.000001)
				)
				(justify left mirror)
			)
		)
		(property "Device Type" "CAPC0063"
			(at 0.148158 1.7526 270)
			(unlocked yes)
			(layer "B.Fab")
			(hide yes)
			(effects
				(font
					(size 1.27 0.9652)
					(thickness 0.000001)
				)
				(justify left mirror)
			)
		)
		(duplicate_pad_numbers_are_jumpers no)
		(fp_circle
			(center 0 0)
			(end 0.127 0)
			(stroke
				(width 0.2032)
				(type default)
			)
			(fill no)
			(layer "B.SilkS")
		)
		(fp_poly
			(pts
				(xy -0.7874 -1.6637) (xy 0.7874 -1.6637) (xy 0.7874 1.6637) (xy -0.7874 1.6637)
			)
			(stroke
				(width 0)
				(type default)
			)
			(fill no)
			(layer "B.CrtYd")
		)
		(fp_line
			(start -0.4064 -0.7874)
			(end -0.4064 0.8128)
			(stroke
				(width 0.0254)
				(type default)
			)
			(layer "B.Fab")
		)
		(fp_line
			(start -0.4064 0.8128)
			(end 0.4064 0.8128)
			(stroke
				(width 0.0254)
				(type default)
			)
			(layer "B.Fab")
		)
		(fp_line
			(start 0.4064 -0.7874)
			(end -0.4064 -0.7874)
			(stroke
				(width 0.0254)
				(type default)
			)
			(layer "B.Fab")
		)
		(fp_line
			(start 0.4064 0.8128)
			(end 0.4064 -0.7874)
			(stroke
				(width 0.0254)
				(type default)
			)
			(layer "B.Fab")
		)
		(pad "1" smd rect
			(at 0 -0.8001 180)
			(size 0.8636 0.9652)
			(layers "B.Cu" "B.Mask" "B.Paste")
			(net "VDD_CORE")
		)
		(pad "2" smd rect
			(at 0 0.8001 180)
			(size 0.8636 0.9652)
			(layers "B.Cu" "B.Mask" "B.Paste")
			(net "GND")
		)
		(zone
			(layer "B.Cu")
			(hatch none 0.5)
			(connect_pads
				(clearance 0)
			)
			(min_thickness 0.25)
			(keepout
				(tracks not_allowed)
				(vias allowed)
				(pads allowed)
				(copperpour not_allowed)
				(footprints allowed)
			)
			(placement
				(enabled no)
				(sheetname "")
			)
			(fill
				(thermal_gap 0.5)
				(thermal_bridge_width 0.5)
				(island_removal_mode 0)
			)
			(polygon
				(pts
					(xy 54.8005 33.528) (xy 54.6735 33.528) (xy 54.6735 34.036) (xy 54.8005 34.036)
				)
			)
		)
	)
	(footprint ""
		(layer "B.Cu")
		(at 49.237011 12.542012)
		(property "Reference" "C178"
			(at 0 0 0)
			(layer "B.SilkS")
			(hide yes)
			(effects
				(font
					(size 1.27 1.27)
				)
				(justify mirror)
			)
		)
		(property "Value" ""
			(at 0 0 0)
			(layer "B.Fab")
			(effects
				(font
					(size 1.27 1.27)
				)
				(justify mirror)
			)
		)
		(duplicate_pad_numbers_are_jumpers no)
		(fp_circle
			(center 0 0)
			(end 0.104648 0)
			(stroke
				(width 0.1016)
				(type default)
			)
			(fill no)
			(layer "B.SilkS")
		)
		(fp_poly
			(pts
				(xy 0.381 -0.889) (xy 0.381 0.889) (xy -0.381 0.889) (xy -0.381 -0.889)
			)
			(stroke
				(width 0)
				(type default)
			)
			(fill no)
			(layer "B.CrtYd")
		)
		(fp_line
			(start -0.508 -1.016)
			(end -0.508 1.016)
			(stroke
				(width 0.0254)
				(type default)
			)
			(layer "B.Fab")
		)
		(fp_line
			(start -0.508 1.016)
			(end 0.508 1.016)
			(stroke
				(width 0.0254)
				(type default)
			)
			(layer "B.Fab")
		)
		(fp_line
			(start 0.254 -1.016)
			(end -0.508 -1.016)
			(stroke
				(width 0.0254)
				(type default)
			)
			(layer "B.Fab")
		)
		(fp_line
			(start 0.508 -1.016)
			(end 0.254 -1.016)
			(stroke
				(width 0.0254)
				(type default)
			)
			(layer "B.Fab")
		)
		(fp_line
			(start 0.508 1.016)
			(end 0.508 -1.016)
			(stroke
				(width 0.0254)
				(type default)
			)
			(layer "B.Fab")
		)
		(pad "1" smd custom
			(at 0 -0.500126 180)
			(size 0.127 0.127)
			(layers "B.Cu" "B.Mask" "B.Paste")
			(net "VDD_CORE")
			(options
				(clearance outline)
				(anchor circle)
			)
			(primitives
				(gr_poly
					(pts
						(xy -0.1778 0.254) (xy 0.1778 0.254) (xy 0.254 0.1778) (xy 0.254 -0.1778) (xy 0.1778 -0.254) (xy -0.1778 -0.254)
						(xy -0.254 -0.1778) (xy -0.254 0.1778)
					)
					(width 0)
					(fill yes)
				)
			)
		)
		(pad "2" smd custom
			(at 0 0.500126 180)
			(size 0.127 0.127)
			(layers "B.Cu" "B.Mask" "B.Paste")
			(net "GND")
			(options
				(clearance outline)
				(anchor circle)
			)
			(primitives
				(gr_poly
					(pts
						(xy -0.1778 0.254) (xy 0.1778 0.254) (xy 0.254 0.1778) (xy 0.254 -0.1778) (xy 0.1778 -0.254) (xy -0.1778 -0.254)
						(xy -0.254 -0.1778) (xy -0.254 0.1778)
					)
					(width 0)
					(fill yes)
				)
			)
		)
	)
	(footprint ""
		(layer "B.Cu")
		(at 39.237031 26.542238 180)
		(property "Reference" "R407"
			(at 0.274701 -2.286762 270)
			(unlocked yes)
			(layer "B.SilkS")
			(effects
				(font
					(size 0.7874 0.5842)
					(thickness 0.127)
				)
				(justify mirror)
			)
		)
		(property "Value" ""
			(at 0 0 0)
			(layer "B.Fab")
			(effects
				(font
					(size 1.27 1.27)
				)
				(justify mirror)
			)
		)
		(duplicate_pad_numbers_are_jumpers no)
		(fp_circle
			(center 0 0)
			(end -0.104648 0)
			(stroke
				(width 0.1016)
				(type default)
			)
			(fill no)
			(layer "B.SilkS")
		)
		(fp_poly
			(pts
				(xy 0.381 -0.889) (xy 0.381 0.889) (xy -0.381 0.889) (xy -0.381 -0.889)
			)
			(stroke
				(width 0)
				(type default)
			)
			(fill no)
			(layer "B.CrtYd")
		)
		(fp_line
			(start 0.508 1.016)
			(end 0.508 -1.016)
			(stroke
				(width 0.0254)
				(type default)
			)
			(layer "B.Fab")
		)
		(fp_line
			(start 0.508 -1.016)
			(end 0.254 -1.016)
			(stroke
				(width 0.0254)
				(type default)
			)
			(layer "B.Fab")
		)
		(fp_line
			(start 0.254 -1.016)
			(end -0.508 -1.016)
			(stroke
				(width 0.0254)
				(type default)
			)
			(layer "B.Fab")
		)
		(fp_line
			(start -0.508 1.016)
			(end 0.508 1.016)
			(stroke
				(width 0.0254)
				(type default)
			)
			(layer "B.Fab")
		)
		(fp_line
			(start -0.508 -1.016)
			(end -0.508 1.016)
			(stroke
				(width 0.0254)
				(type default)
			)
			(layer "B.Fab")
		)
		(pad "1" smd custom
			(at 0 -0.500126)
			(size 0.127 0.127)
			(layers "B.Cu" "B.Mask" "B.Paste")
			(net "NFP_JTAG_ARM_TRST_L")
			(options
				(clearance outline)
				(anchor circle)
			)
			(primitives
				(gr_poly
					(pts
						(xy -0.1778 0.254) (xy 0.1778 0.254) (xy 0.254 0.1778) (xy 0.254 -0.1778) (xy 0.1778 -0.254) (xy -0.1778 -0.254)
						(xy -0.254 -0.1778) (xy -0.254 0.1778)
					)
					(width 0)
					(fill yes)
				)
			)
		)
		(pad "2" smd custom
			(at 0 0.500126)
			(size 0.127 0.127)
			(layers "B.Cu" "B.Mask" "B.Paste")
			(net "GND")
			(options
				(clearance outline)
				(anchor circle)
			)
			(primitives
				(gr_poly
					(pts
						(xy -0.1778 0.254) (xy 0.1778 0.254) (xy 0.254 0.1778) (xy 0.254 -0.1778) (xy 0.1778 -0.254) (xy -0.1778 -0.254)
						(xy -0.254 -0.1778) (xy -0.254 0.1778)
					)
					(width 0)
					(fill yes)
				)
			)
		)
	)
	(footprint ""
		(layer "B.Cu")
		(at 51.94808 35.41776 90)
		(property "Reference" "R118"
			(at -1.55067 1.6891 0)
			(unlocked yes)
			(layer "B.SilkS")
			(effects
				(font
					(size 0.7874 0.5842)
					(thickness 0.127)
				)
				(justify left mirror)
			)
		)
		(property "Value" "2.2"
			(at 0.148158 1.7526 0)
			(unlocked yes)
			(layer "B.Fab")
			(hide yes)
			(effects
				(font
					(size 1.27 0.9652)
					(thickness 0.000001)
				)
				(justify left mirror)
			)
		)
		(property "Device Type" "REST0145"
			(at 0.148158 1.7526 0)
			(unlocked yes)
			(layer "B.Fab")
			(hide yes)
			(effects
				(font
					(size 1.27 0.9652)
					(thickness 0.000001)
				)
				(justify left mirror)
			)
		)
		(duplicate_pad_numbers_are_jumpers no)
		(fp_circle
			(center 0 0)
			(end 0 0.127)
			(stroke
				(width 0.2032)
				(type default)
			)
			(fill no)
			(layer "B.SilkS")
		)
		(fp_poly
			(pts
				(xy -0.7874 -1.6637) (xy 0.7874 -1.6637) (xy 0.7874 1.6637) (xy -0.7874 1.6637)
			)
			(stroke
				(width 0)
				(type default)
			)
			(fill no)
			(layer "B.CrtYd")
		)
		(fp_line
			(start 0.4064 -0.8128)
			(end -0.4064 -0.8128)
			(stroke
				(width 0.0254)
				(type default)
			)
			(layer "B.Fab")
		)
		(fp_line
			(start -0.4064 -0.8128)
			(end -0.4064 0.8128)
			(stroke
				(width 0.0254)
				(type default)
			)
			(layer "B.Fab")
		)
		(fp_line
			(start 0.4064 0.8128)
			(end 0.4064 -0.8128)
			(stroke
				(width 0.0254)
				(type default)
			)
			(layer "B.Fab")
		)
		(fp_line
			(start -0.4064 0.8128)
			(end 0.4064 0.8128)
			(stroke
				(width 0.0254)
				(type default)
			)
			(layer "B.Fab")
		)
		(pad "1" smd rect
			(at 0 -0.8001 270)
			(size 0.762 0.9652)
			(layers "B.Cu" "B.Mask" "B.Paste")
			(net "10N2233")
		)
		(pad "2" smd rect
			(at 0 0.8001 270)
			(size 0.762 0.9652)
			(layers "B.Cu" "B.Mask" "B.Paste")
			(net "10N2259")
		)
		(zone
			(layer "B.Cu")
			(hatch none 0.5)
			(connect_pads
				(clearance 0)
			)
			(min_thickness 0.25)
			(keepout
				(tracks not_allowed)
				(vias allowed)
				(pads allowed)
				(copperpour not_allowed)
				(footprints allowed)
			)
			(placement
				(enabled no)
				(sheetname "")
			)
			(fill
				(thermal_gap 0.5)
				(thermal_bridge_width 0.5)
				(island_removal_mode 0)
			)
			(polygon
				(pts
					(xy 51.69408 35.35426) (xy 51.69408 35.48126) (xy 52.20208 35.48126) (xy 52.20208 35.35426)
				)
			)
		)
	)
	(footprint ""
		(layer "B.Cu")
		(at 66.929 23.622 90)
		(property "Reference" "R272"
			(at 0.98933 2.032 0)
			(unlocked yes)
			(layer "B.SilkS")
			(effects
				(font
					(size 0.7874 0.5842)
					(thickness 0.127)
				)
				(justify mirror)
			)
		)
		(property "Value" ""
			(at 0 0 90)
			(layer "B.Fab")
			(effects
				(font
					(size 1.27 1.27)
				)
				(justify mirror)
			)
		)
		(duplicate_pad_numbers_are_jumpers no)
		(fp_circle
			(center 0 0)
			(end 0 0.104648)
			(stroke
				(width 0.1016)
				(type default)
			)
			(fill no)
			(layer "B.SilkS")
		)
		(fp_poly
			(pts
				(xy 0.381 -0.889) (xy 0.381 0.889) (xy -0.381 0.889) (xy -0.381 -0.889)
			)
			(stroke
				(width 0)
				(type default)
			)
			(fill no)
			(layer "B.CrtYd")
		)
		(fp_line
			(start 0.508 -1.016)
			(end 0.254 -1.016)
			(stroke
				(width 0.0254)
				(type default)
			)
			(layer "B.Fab")
		)
		(fp_line
			(start 0.254 -1.016)
			(end -0.508 -1.016)
			(stroke
				(width 0.0254)
				(type default)
			)
			(layer "B.Fab")
		)
		(fp_line
			(start -0.508 -1.016)
			(end -0.508 1.016)
			(stroke
				(width 0.0254)
				(type default)
			)
			(layer "B.Fab")
		)
		(fp_line
			(start 0.508 1.016)
			(end 0.508 -1.016)
			(stroke
				(width 0.0254)
				(type default)
			)
			(layer "B.Fab")
		)
		(fp_line
			(start -0.508 1.016)
			(end 0.508 1.016)
			(stroke
				(width 0.0254)
				(type default)
			)
			(layer "B.Fab")
		)
		(pad "1" smd custom
			(at 0 -0.500126 270)
			(size 0.127 0.127)
			(layers "B.Cu" "B.Mask" "B.Paste")
			(net "6N3961")
			(options
				(clearance outline)
				(anchor circle)
			)
			(primitives
				(gr_poly
					(pts
						(xy -0.1778 0.254) (xy 0.1778 0.254) (xy 0.254 0.1778) (xy 0.254 -0.1778) (xy 0.1778 -0.254) (xy -0.1778 -0.254)
						(xy -0.254 -0.1778) (xy -0.254 0.1778)
					)
					(width 0)
					(fill yes)
				)
			)
		)
		(pad "2" smd custom
			(at 0 0.500126 270)
			(size 0.127 0.127)
			(layers "B.Cu" "B.Mask" "B.Paste")
			(net "DDR0_32A_DRAMRST_L")
			(options
				(clearance outline)
				(anchor circle)
			)
			(primitives
				(gr_poly
					(pts
						(xy -0.1778 0.254) (xy 0.1778 0.254) (xy 0.254 0.1778) (xy 0.254 -0.1778) (xy 0.1778 -0.254) (xy -0.1778 -0.254)
						(xy -0.254 -0.1778) (xy -0.254 0.1778)
					)
					(width 0)
					(fill yes)
				)
			)
		)
	)
	(footprint ""
		(layer "B.Cu")
		(at 61.849 47.625)
		(property "Reference" "TP35"
			(at 0.889 1.80467 0)
			(unlocked yes)
			(layer "B.SilkS")
			(effects
				(font
					(size 0.7874 0.5842)
					(thickness 0.127)
				)
				(justify left mirror)
			)
		)
		(property "Value" "*"
			(at 0.4826 -0.14732 0)
			(unlocked yes)
			(layer "B.Fab")
			(hide yes)
			(effects
				(font
					(size 1.27 0.9652)
					(thickness 0.000001)
				)
				(justify left mirror)
			)
		)
		(property "Device Type" "TP_SMALL"
			(at 0.4826 -0.14732 0)
			(unlocked yes)
			(layer "B.Fab")
			(hide yes)
			(effects
				(font
					(size 1.27 0.9652)
					(thickness 0.000001)
				)
				(justify left mirror)
			)
		)
		(duplicate_pad_numbers_are_jumpers no)
		(fp_line
			(start -0.8636 -0.8636)
			(end 0.8636 -0.8636)
			(stroke
				(width 0.1524)
				(type default)
			)
			(layer "B.SilkS")
		)
		(fp_line
			(start -0.8636 0.8636)
			(end -0.8636 -0.8636)
			(stroke
				(width 0.1524)
				(type default)
			)
			(layer "B.SilkS")
		)
		(fp_line
			(start 0.8636 -0.8636)
			(end 0.8636 0.8636)
			(stroke
				(width 0.1524)
				(type default)
			)
			(layer "B.SilkS")
		)
		(fp_line
			(start 0.8636 0.8636)
			(end -0.8636 0.8636)
			(stroke
				(width 0.1524)
				(type default)
			)
			(layer "B.SilkS")
		)
		(fp_poly
			(pts
				(xy 0.635 -0.635) (xy 0.635 0.635) (xy -0.635 0.635) (xy -0.635 -0.635)
			)
			(stroke
				(width 0)
				(type default)
			)
			(fill no)
			(layer "B.CrtYd")
		)
		(pad "1" smd rect
			(at 0 0 180)
			(size 1.27 1.27)
			(layers "B.Cu" "B.Mask" "B.Paste")
			(net "CORE_FB_PH1_THERM_L")
		)
	)
	(footprint ""
		(layer "B.Cu")
		(at 26.924 22.2758 180)
		(property "Reference" "R47"
			(at 0.15367 -2.8702 270)
			(unlocked yes)
			(layer "B.SilkS")
			(effects
				(font
					(size 0.7874 0.5842)
					(thickness 0.127)
				)
				(justify left mirror)
			)
		)
		(property "Value" "4.75K"
			(at 0.148158 1.3462 90)
			(unlocked yes)
			(layer "B.Fab")
			(hide yes)
			(effects
				(font
					(size 1.27 0.9652)
					(thickness 0.000001)
				)
				(justify left mirror)
			)
		)
		(property "Device Type" "REST4024"
			(at 0.148158 1.3462 90)
			(unlocked yes)
			(layer "B.Fab")
			(hide yes)
			(effects
				(font
					(size 1.27 0.9652)
					(thickness 0.000001)
				)
				(justify left mirror)
			)
		)
		(duplicate_pad_numbers_are_jumpers no)
		(fp_poly
			(pts
				(xy -0.635 1.0668) (xy -0.635 -1.0668) (xy 0.635 -1.0668) (xy 0.635 1.0668)
			)
			(stroke
				(width 0)
				(type default)
			)
			(fill no)
			(layer "B.CrtYd")
		)
		(fp_line
			(start 0.254 0.508)
			(end 0.254 -0.508)
			(stroke
				(width 0.0254)
				(type default)
			)
			(layer "B.Fab")
		)
		(fp_line
			(start 0.254 -0.508)
			(end -0.254 -0.508)
			(stroke
				(width 0.0254)
				(type default)
			)
			(layer "B.Fab")
		)
		(fp_line
			(start -0.254 0.508)
			(end 0.254 0.508)
			(stroke
				(width 0.0254)
				(type default)
			)
			(layer "B.Fab")
		)
		(fp_line
			(start -0.254 -0.508)
			(end -0.254 0.508)
			(stroke
				(width 0.0254)
				(type default)
			)
			(layer "B.Fab")
		)
		(pad "1" smd rect
			(at 0 -0.4191)
			(size 0.508 0.5334)
			(layers "B.Cu" "B.Mask" "B.Paste")
			(net "_NFP_CLK_NRESET_L")
		)
		(pad "2" smd rect
			(at 0 0.4191)
			(size 0.508 0.5334)
			(layers "B.Cu" "B.Mask" "B.Paste")
			(net "GND")
		)
		(zone
			(layer "B.Cu")
			(hatch none 0.5)
			(connect_pads
				(clearance 0)
			)
			(min_thickness 0.25)
			(keepout
				(tracks not_allowed)
				(vias allowed)
				(pads allowed)
				(copperpour not_allowed)
				(footprints allowed)
			)
			(placement
				(enabled no)
				(sheetname "")
			)
			(fill
				(thermal_gap 0.5)
				(thermal_bridge_width 0.5)
				(island_removal_mode 0)
			)
			(polygon
				(pts
					(xy 26.9494 22.3012) (xy 26.9494 22.2504) (xy 26.8986 22.2504) (xy 26.8986 22.3012)
				)
			)
		)
	)
	(footprint ""
		(layer "B.Cu")
		(at 29.083 40.513)
		(property "Reference" "TP39"
			(at 3.937 -0.35433 0)
			(unlocked yes)
			(layer "B.SilkS")
			(effects
				(font
					(size 0.7874 0.5842)
					(thickness 0.127)
				)
				(justify left mirror)
			)
		)
		(property "Value" "*"
			(at 0.4826 -0.14732 0)
			(unlocked yes)
			(layer "B.Fab")
			(hide yes)
			(effects
				(font
					(size 1.27 0.9652)
					(thickness 0.000001)
				)
				(justify left mirror)
			)
		)
		(property "Device Type" "TP_SMALL"
			(at 0.4826 -0.14732 0)
			(unlocked yes)
			(layer "B.Fab")
			(hide yes)
			(effects
				(font
					(size 1.27 0.9652)
					(thickness 0.000001)
				)
				(justify left mirror)
			)
		)
		(duplicate_pad_numbers_are_jumpers no)
		(fp_line
			(start -0.8636 -0.8636)
			(end 0.8636 -0.8636)
			(stroke
				(width 0.1524)
				(type default)
			)
			(layer "B.SilkS")
		)
		(fp_line
			(start -0.8636 0.8636)
			(end -0.8636 -0.8636)
			(stroke
				(width 0.1524)
				(type default)
			)
			(layer "B.SilkS")
		)
		(fp_line
			(start 0.8636 -0.8636)
			(end 0.8636 0.8636)
			(stroke
				(width 0.1524)
				(type default)
			)
			(layer "B.SilkS")
		)
		(fp_line
			(start 0.8636 0.8636)
			(end -0.8636 0.8636)
			(stroke
				(width 0.1524)
				(type default)
			)
			(layer "B.SilkS")
		)
		(fp_poly
			(pts
				(xy 0.635 -0.635) (xy 0.635 0.635) (xy -0.635 0.635) (xy -0.635 -0.635)
			)
			(stroke
				(width 0)
				(type default)
			)
			(fill no)
			(layer "B.CrtYd")
		)
		(pad "1" smd rect
			(at 0 0 180)
			(size 1.27 1.27)
			(layers "B.Cu" "B.Mask" "B.Paste")
			(net "GND")
		)
	)
	(footprint ""
		(layer "B.Cu")
		(at 84.250987 2.699004)
		(property "Reference" "V1_A-A13"
			(at 0 0 0)
			(layer "B.SilkS")
			(hide yes)
			(effects
				(font
					(size 1.27 1.27)
				)
				(justify mirror)
			)
		)
		(property "Value" ""
			(at 0 0 0)
			(layer "B.Fab")
			(effects
				(font
					(size 1.27 1.27)
				)
				(justify mirror)
			)
		)
		(duplicate_pad_numbers_are_jumpers no)
		(pad "1" thru_hole circle
			(at 0 0 180)
			(size 0.4572 0.4572)
			(drill 0.20574)
			(layers "*.Cu" "*.Mask")
			(remove_unused_layers no)
			(net "DDR0_32A_A13")
			(clearance 0.1143)
			(thermal_gap 0.1143)
		)
	)
	(footprint ""
		(layer "B.Cu")
		(at 83.450989 25.013006)
		(property "Reference" "V3_A-A07"
			(at 0 0 0)
			(layer "B.SilkS")
			(hide yes)
			(effects
				(font
					(size 1.27 1.27)
				)
				(justify mirror)
			)
		)
		(property "Value" ""
			(at 0 0 0)
			(layer "B.Fab")
			(effects
				(font
					(size 1.27 1.27)
				)
				(justify mirror)
			)
		)
		(duplicate_pad_numbers_are_jumpers no)
		(pad "1" thru_hole circle
			(at 0 0 180)
			(size 0.4572 0.4572)
			(drill 0.20574)
			(layers "*.Cu" "*.Mask")
			(remove_unused_layers no)
			(net "DDR0_32A_A7")
			(clearance 0.1143)
			(thermal_gap 0.1143)
		)
	)
)
